# S9S_MB_2U (Grand Teton) — schematic netlist excerpt (pin names and nets, part order shuffled) for the footprints in the layout excerpt that follows; sources: Cadence DE-HDL packaged netlist, KiCad conversion of 03242023_DA0F0TMBIJ0_F0T_Motherboard_J_brd_V01_OCP.brd

J19  SCONN288_ADR50017P130CC  SCONN288_ADR50017-P130CC IO  pkg DDR288S_1-1VXB  page 100
  VIN_BULK0  = P12V_S3_AUX_CPU1_NVDIMM
  RFU0  = TP_CHB_CPU1_DIMM1_FRU_0
  VIN_MGMT  = P3V3_AUX
  HSCL  = I3C_SPD_DDRABCD_CPU1_LVC1_SCL_2
  HSDA  = I3C_SPD_DDRABCD_CPU1_LVC1_SDA
  VSS0  = GND
  DQ0_A  = M_B_CPU1_SA_DQ<0>
  VSS1  = GND
  DQ1_A  = M_B_CPU1_SA_DQ<1>
  VSS2  = GND
  DQS0_A_T  = M_B_CPU1_SA_DQS_DP<0>
  DQS0_A_C  = M_B_CPU1_SA_DQS_DN<0>
  VSS3  = GND
  DQ4_A  = M_B_CPU1_SA_DQ<4>
  VSS4  = GND
  DQ5_A  = M_B_CPU1_SA_DQ<5>
  VSS5  = GND
  DQ8_A  = M_B_CPU1_SA_DQ<8>
  VSS6  = GND
  DQ9_A  = M_B_CPU1_SA_DQ<9>
  VSS7  = GND
  DQS1_A_T  = M_B_CPU1_SA_DQS_DP<1>
  DQS1_A_C  = M_B_CPU1_SA_DQS_DN<1>
  VSS8  = GND
  DQ12_A  = M_B_CPU1_SA_DQ<12>
  VSS9  = GND
  DQ13_A  = M_B_CPU1_SA_DQ<13>
  VSS10  = GND
  DQ16_A  = M_B_CPU1_SA_DQ<16>
  VSS11  = GND
  DQ17_A  = M_B_CPU1_SA_DQ<17>
  VSS12  = GND
  DQS2_A_T  = M_B_CPU1_SA_DQS_DP<2>
  DQS2_A_C  = M_B_CPU1_SA_DQS_DN<2>
  VSS13  = GND
  DQ20_A  = M_B_CPU1_SA_DQ<20>
  VSS14  = GND
  DQ21_A  = M_B_CPU1_SA_DQ<21>
  VSS15  = GND
  DQ24_A  = M_B_CPU1_SA_DQ<24>
  VSS16  = GND
  DQ25_A  = M_B_CPU1_SA_DQ<25>
  VSS17  = GND
  DQS3_A_T  = M_B_CPU1_SA_DQS_DP<3>
  DQS3_A_C  = M_B_CPU1_SA_DQS_DN<3>
  VSS18  = GND
  DQ28_A  = M_B_CPU1_SA_DQ<28>
  VSS19  = GND
  DQ29_A  = M_B_CPU1_SA_DQ<29>
  VSS20  = GND
  CB0_A  = M_B_CPU1_SA_CB<0>
  VSS21  = GND
  CB1_A  = M_B_CPU1_SA_CB<1>
  VSS22  = GND
  DQS4_A_T  = M_B_CPU1_SA_DQS_DP<4>
  DQS4_A_C  = M_B_CPU1_SA_DQS_DN<4>
  VSS23  = GND
  CB4_A  = M_B_CPU1_SA_CB<4>
  VSS24  = GND
  CB5_A  = M_B_CPU1_SA_CB<5>
  VSS25  = GND
  ALERT_N  = M_B_CPU1_ALERT_N
  VSS26  = GND
  CS0_A_N  = M_B_CPU1_SA_CS_N<0>
  VSS27  = GND
  CA0_A  = M_B_CPU1_SA_CA<0>
  VSS28  = GND
  CA2_A  = M_B_CPU1_SA_CA<2>
  VSS29  = GND
  CA4_A  = M_B_CPU1_SA_CA<4>
  VSS30  = GND
  CA6_A  = M_B_CPU1_SA_CA<6>
  VSS31  = GND
  PAR_A  = M_B_CPU1_SA_PAR
  VSS32  = GND
  CA0_B  = M_B_CPU1_SB_CA<0>
  VSS33  = GND
  CA2_B  = M_B_CPU1_SB_CA<2>
  VSS34  = GND
  CA4_B  = M_B_CPU1_SB_CA<4>
  VSS35  = GND
  CA6_B  = M_B_CPU1_SB_CA<6>
  VSS36  = GND
  CS0_B_N  = M_B_CPU1_SB_CS_N<0>
  VSS37  = GND
  \lbd||rsp_a_n\  = M_B_CPU1_SA_RSP<0>
  \lbs||rsp_b_n\  = M_B_CPU1_SB_RSP<0>
  VSS38  = GND
  CB4_B  = M_B_CPU1_SB_CB<4>
  VSS39  = GND
  CB5_B  = M_B_CPU1_SB_CB<5>
  VSS40  = GND
  \dqs9_b_t||tdqs9_b_t||dbi4_b_n\  = M_B_CPU1_SB_DQS_DP<9>
  \dqs9_b_c||tdqs9_b_c\  = M_B_CPU1_SB_DQS_DN<9>
  VSS41  = GND
  CB0_B  = M_B_CPU1_SB_CB<0>
  VSS42  = GND
  CB1_B  = M_B_CPU1_SB_CB<1>
  VSS43  = GND
  DQ0_B  = M_B_CPU1_SB_DQ<0>
  VSS44  = GND
  DQ1_B  = M_B_CPU1_SB_DQ<1>
  VSS45  = GND
  DQS0_B_T  = M_B_CPU1_SB_DQS_DP<0>
  DQS0_B_C  = M_B_CPU1_SB_DQS_DN<0>
  VSS46  = GND
  DQ4_B  = M_B_CPU1_SB_DQ<4>
  VSS47  = GND
  DQ5_B  = M_B_CPU1_SB_DQ<5>
  VSS48  = GND
  DQ8_B  = M_B_CPU1_SB_DQ<8>
  VSS49  = GND
  DQ9_B  = M_B_CPU1_SB_DQ<9>
  VSS50  = GND
  DQS1_B_T  = M_B_CPU1_SB_DQS_DP<1>
  DQS1_B_C  = M_B_CPU1_SB_DQS_DN<1>
  VSS51  = GND
  DQ12_B  = M_B_CPU1_SB_DQ<12>
  VSS52  = GND
  DQ13_B  = M_B_CPU1_SB_DQ<13>
  VSS53  = GND
  DQ16_B  = M_B_CPU1_SB_DQ<16>
  VSS54  = GND
  DQ17_B  = M_B_CPU1_SB_DQ<17>
  VSS55  = GND
  DQS2_B_T  = M_B_CPU1_SB_DQS_DP<2>
  DQS2_B_C  = M_B_CPU1_SB_DQS_DN<2>
  VSS56  = GND
  DQ20_B  = M_B_CPU1_SB_DQ<20>
  VSS57  = GND
  DQ21_B  = M_B_CPU1_SB_DQ<21>
  VSS58  = GND
  DQ24_B  = M_B_CPU1_SB_DQ<24>
  VSS59  = GND
  DQ25_B  = M_B_CPU1_SB_DQ<25>
  VSS60  = GND
  DQS3_B_T  = M_B_CPU1_SB_DQS_DP<3>
  DQS3_B_C  = M_B_CPU1_SB_DQS_DN<3>
  VSS61  = GND
  DQ28_B  = M_B_CPU1_SB_DQ<28>
  VSS62  = GND
  DQ29_B  = M_B_CPU1_SB_DQ<29>
  VSS63  = GND
  RFU1  = TP_CHB_CPU1_DIMM1_FRU_1
  VIN_BULK1  = P12V_S3_AUX_CPU1_NVDIMM
  VIN_BULK2  = P12V_S3_AUX_CPU1_NVDIMM
  \pwr_good||fail_n\  = PWRGD_CHB_CPU1_DIMM1
  HSA  = PD_CHB_CPU1_DIMM1_SAA
  RFU2  = TP_CHB_CPU1_DIMM1_FRU_2
  RFU3  = TP_CHB_CPU1_DIMM1_FRU_3
  VSS64  = GND
  DQ2_A  = M_B_CPU1_SA_DQ<2>
  VSS65  = GND
  DQ3_A  = M_B_CPU1_SA_DQ<3>
  VSS66  = GND
  \dqs5_a_c||tdqs5_a_c||dqs5_a_t||tdqs5_a_t\  = M_B_CPU1_SA_DQS_DN<5>
  \dqs5_a_t||tdqs5_a_t\  = M_B_CPU1_SA_DQS_DP<5>
  VSS67  = GND
  DQ6_A  = M_B_CPU1_SA_DQ<6>
  VSS68  = GND
  DQ7_A  = M_B_CPU1_SA_DQ<7>
  VSS69  = GND
  DQ10_A  = M_B_CPU1_SA_DQ<10>
  VSS70  = GND
  DQ11_A  = M_B_CPU1_SA_DQ<11>
  VSS71  = GND
  \dqs6_a_c||tdqs6_a_c||dqs6_a_t||tdqs6_a_t\  = M_B_CPU1_SA_DQS_DN<6>
  \dqs6_a_t||tdqs6_a_t\  = M_B_CPU1_SA_DQS_DP<6>
  VSS72  = GND
  DQ14_A  = M_B_CPU1_SA_DQ<14>
  VSS73  = GND
  DQ15_A  = M_B_CPU1_SA_DQ<15>
  VSS74  = GND
  DQ18_A  = M_B_CPU1_SA_DQ<18>
  VSS75  = GND
  DQ19_A  = M_B_CPU1_SA_DQ<19>
  VSS76  = GND
  \dqs7_a_c||tdqs7_a_c\  = M_B_CPU1_SA_DQS_DN<7>
  \dqs7_a_t||tdqs7_a_t\  = M_B_CPU1_SA_DQS_DP<7>
  VSS77  = GND
  DQ22_A  = M_B_CPU1_SA_DQ<22>
  VSS78  = GND
  DQ23_A  = M_B_CPU1_SA_DQ<23>
  VSS79  = GND
  DQ26_A  = M_B_CPU1_SA_DQ<26>
  VSS80  = GND
  DQ27_A  = M_B_CPU1_SA_DQ<27>
  VSS81  = GND
  \dqs8_a_c||tdqs8_a_c\  = M_B_CPU1_SA_DQS_DN<8>
  \dqs8_a_t||tdqs8_a_t\  = M_B_CPU1_SA_DQS_DP<8>
  VSS82  = GND
  DQ30_A  = M_B_CPU1_SA_DQ<30>
  VSS83  = GND
  DQ31_A  = M_B_CPU1_SA_DQ<31>
  VSS84  = GND
  CB2_A  = M_B_CPU1_SA_CB<2>
  VSS85  = GND
  CB3_A  = M_B_CPU1_SA_CB<3>
  VSS86  = GND
  \dqs9_a_c||tdqs9_a_c\  = M_B_CPU1_SA_DQS_DN<9>
  \dqs9_a_t||tdqs9_a_t\  = M_B_CPU1_SA_DQS_DP<9>
  VSS87  = GND
  CB6_A  = M_B_CPU1_SA_CB<6>
  VSS88  = GND
  CB7_A  = M_B_CPU1_SA_CB<7>
  VSS89  = GND
  RESET_N  = RST_M_AB_CPU1_FPGA_N
  VSS90  = GND
  CS1_A_N  = M_B_CPU1_SA_CS_N<1>
  VSS91  = GND
  CA1_A  = M_B_CPU1_SA_CA<1>
  VSS92  = GND
  CA3_A  = M_B_CPU1_SA_CA<3>
  VSS93  = GND
  CA5_A  = M_B_CPU1_SA_CA<5>
  VSS94  = GND
  CK_T  = M_B_CPU1_CLK_DP<0>
  CK_C  = M_B_CPU1_CLK_DN<0>
  VSS95  = GND
  RFU4  = TP_CHB_CPU1_DIMM1_FRU_4
  CA1_B  = M_B_CPU1_SB_CA<1>
  VSS96  = GND
  CA3_B  = M_B_CPU1_SB_CA<3>
  VSS97  = GND
  CA5_B  = M_B_CPU1_SB_CA<5>
  VSS98  = GND
  PAR_B  = M_B_CPU1_SB_PAR
  VSS99  = GND
  CS1_B_N  = M_B_CPU1_SB_CS_N<1>
  VSS100  = GND
  RFU5  = TP_CHB_CPU1_DIMM1_FRU_5
  RFU6  = TP_CHB_CPU1_DIMM1_FRU_6
  VSS101  = GND
  CB6_B  = M_B_CPU1_SB_CB<6>
  VSS102  = GND
  CB7_B  = M_B_CPU1_SB_CB<7>
  VSS103  = GND
  DQS4_B_C  = M_B_CPU1_SB_DQS_DN<4>
  DQS4_B_T  = M_B_CPU1_SB_DQS_DP<4>
  VSS104  = GND
  CB2_B  = M_B_CPU1_SB_CB<2>
  VSS105  = GND
  CB3_B  = M_B_CPU1_SB_CB<3>
  VSS106  = GND
  DQ2_B  = M_B_CPU1_SB_DQ<2>
  VSS107  = GND
  DQ3_B  = M_B_CPU1_SB_DQ<3>
  VSS108  = GND
  \dqs5_b_c||tdqs5_b_c\  = M_B_CPU1_SB_DQS_DN<5>
  \dqs5_b_t||tdqs5_b_t\  = M_B_CPU1_SB_DQS_DP<5>
  VSS109  = GND
  DQ6_B  = M_B_CPU1_SB_DQ<6>
  VSS110  = GND
  DQ7_B  = M_B_CPU1_SB_DQ<7>
  VSS111  = GND
  DQ10_B  = M_B_CPU1_SB_DQ<10>
  VSS112  = GND
  DQ11_B  = M_B_CPU1_SB_DQ<11>
  VSS113  = GND
  \dqs6_b_c||tdqs6_b_c\  = M_B_CPU1_SB_DQS_DN<6>
  \dqs6_b_t||tdqs6_b_t\  = M_B_CPU1_SB_DQS_DP<6>
  VSS114  = GND
  DQ14_B  = M_B_CPU1_SB_DQ<14>
  VSS115  = GND
  DQ15_B  = M_B_CPU1_SB_DQ<15>
  VSS116  = GND
  DQ18_B  = M_B_CPU1_SB_DQ<18>
  VSS117  = GND
  DQ19_B  = M_B_CPU1_SB_DQ<19>
  VSS118  = GND
  \dqs7_b_c||tdqs7_b_c\  = M_B_CPU1_SB_DQS_DN<7>
  \dqs7_b_t||tdqs7_b_t\  = M_B_CPU1_SB_DQS_DP<7>
  VSS119  = GND
  DQ22_B  = M_B_CPU1_SB_DQ<22>
  VSS120  = GND
  DQ23_B  = M_B_CPU1_SB_DQ<23>
  VSS121  = GND
  DQ26_B  = M_B_CPU1_SB_DQ<26>
  VSS122  = GND
  DQ27_B  = M_B_CPU1_SB_DQ<27>
  VSS123  = GND
  \dqs8_b_c||tdqs8_b_c\  = M_B_CPU1_SB_DQS_DN<8>
  \dqs8_b_t||tdqs8_b_t\  = M_B_CPU1_SB_DQS_DP<8>
  VSS124  = GND
  DQ30_B  = M_B_CPU1_SB_DQ<30>
  VSS125  = GND
  DQ31_B  = M_B_CPU1_SB_DQ<31>
  VSS126  = GND
  G1  = GND
  G2  = GND
  G3  = GND

(kicad_pcb
	(version 20260206)
	(generator "pcbnew")
	(generator_version "10.0")
	(general
		(thickness 1.6)
		(legacy_teardrops no)
	)
	(paper "A4")
	(title_block
		(title "03242023_DA0F0TMBIJ0_F0T_Motherboard_J_brd_V01_OCP.brd")
		(comment 1 "Grand Teton / footprint 2188 of 6105 (J19), pads 46-91 of 291")
	)
	(layers
		(0 "F.Cu" signal "TOP")
		(4 "In1.Cu" signal "GND")
		(6 "In2.Cu" signal "IN1")
		(8 "In3.Cu" signal "GND1")
		(10 "In4.Cu" signal "IN2")
		(12 "In5.Cu" signal "GND2")
		(14 "In6.Cu" signal "IN3")
		(16 "In7.Cu" signal "GND3")
		(18 "In8.Cu" signal "VCC")
		(20 "In9.Cu" signal "VCC1")
		(22 "In10.Cu" signal "GND4")
		(24 "In11.Cu" signal "IN4")
		(26 "In12.Cu" signal "GND5")
		(28 "In13.Cu" signal "IN5")
		(30 "In14.Cu" signal "GND6")
		(32 "In15.Cu" signal "IN6")
		(34 "In16.Cu" signal "GND7")
		(2 "B.Cu" signal "BOTTOM")
		(9 "F.Adhes" user "F.Adhesive")
		(11 "B.Adhes" user "B.Adhesive")
		(13 "F.Paste" user "Package Geometry/Pastemask Top")
		(15 "B.Paste" user "Package Geometry/Pastemask Bottom")
		(5 "F.SilkS" user "Ref Des/Silkscreen Top")
		(7 "B.SilkS" user "Ref Des/Silkscreen Bottom")
		(1 "F.Mask" user "Board Geometry/Soldermask Top")
		(3 "B.Mask" user "Board Geometry/Soldermask Bottom")
		(17 "Dwgs.User" user "User.Drawings")
		(19 "Cmts.User" user "User.Comments")
		(21 "Eco1.User" user "User.Eco1")
		(23 "Eco2.User" user "User.Eco2")
		(25 "Edge.Cuts" user "Board Geometry/Outline")
		(27 "Margin" user)
		(31 "F.CrtYd" user "Package Geometry/Place Bound Top")
		(29 "B.CrtYd" user "Package Geometry/Place Bound Bottom")
		(35 "F.Fab" user "Ref Des/Assembly Top")
		(33 "B.Fab" user "Ref Des/Assembly Bottom")
	)
	(footprint ""
		(layer "F.Cu")
		(at 40.36568 -258.091686)
		(property "Reference" "J19"
			(at -5.21716 -81.970372 0)
			(unlocked yes)
			(layer "F.SilkS")
			(effects
				(font
					(size 0.7874 0.5842)
					(thickness 0.1524)
				)
				(justify left)
			)
		)
		(property "Value" ""
			(at 0 0 0)
			(layer "F.Fab")
			(effects
				(font
					(size 1.27 1.27)
				)
			)
		)
		(duplicate_pad_numbers_are_jumpers no)
		(pad "46" smd rect
			(at -2.050034 -25.07488 270)
			(size 0.519938 1.4986)
			(layers "F.Cu" "F.Mask" "F.Paste")
			(net "GND")
		)
		(pad "47" smd rect
			(at -2.050034 -24.224996 270)
			(size 0.519938 1.4986)
			(layers "F.Cu" "F.Mask" "F.Paste")
			(net "M_B_CPU1_SA_DQ<28>")
		)
		(pad "48" smd rect
			(at -2.050034 -23.375112 270)
			(size 0.519938 1.4986)
			(layers "F.Cu" "F.Mask" "F.Paste")
			(net "GND")
		)
		(pad "49" smd rect
			(at -2.050034 -22.524974 270)
			(size 0.519938 1.4986)
			(layers "F.Cu" "F.Mask" "F.Paste")
			(net "M_B_CPU1_SA_DQ<29>")
		)
		(pad "50" smd rect
			(at -2.050034 -21.67509 270)
			(size 0.519938 1.4986)
			(layers "F.Cu" "F.Mask" "F.Paste")
			(net "GND")
		)
		(pad "51" smd rect
			(at -2.050034 -20.824952 270)
			(size 0.519938 1.4986)
			(layers "F.Cu" "F.Mask" "F.Paste")
			(net "M_B_CPU1_SA_CB<0>")
		)
		(pad "52" smd rect
			(at -2.050034 -19.975068 270)
			(size 0.519938 1.4986)
			(layers "F.Cu" "F.Mask" "F.Paste")
			(net "GND")
		)
		(pad "53" smd rect
			(at -2.050034 -19.12493 270)
			(size 0.519938 1.4986)
			(layers "F.Cu" "F.Mask" "F.Paste")
			(net "M_B_CPU1_SA_CB<1>")
		)
		(pad "54" smd rect
			(at -2.050034 -18.275046 270)
			(size 0.519938 1.4986)
			(layers "F.Cu" "F.Mask" "F.Paste")
			(net "GND")
		)
		(pad "55" smd rect
			(at -2.050034 -17.424908 270)
			(size 0.519938 1.4986)
			(layers "F.Cu" "F.Mask" "F.Paste")
			(net "M_B_CPU1_SA_DQS_DP<4>")
		)
		(pad "56" smd rect
			(at -2.050034 -16.575024 270)
			(size 0.519938 1.4986)
			(layers "F.Cu" "F.Mask" "F.Paste")
			(net "M_B_CPU1_SA_DQS_DN<4>")
		)
		(pad "57" smd rect
			(at -2.050034 -15.724886 270)
			(size 0.519938 1.4986)
			(layers "F.Cu" "F.Mask" "F.Paste")
			(net "GND")
		)
		(pad "58" smd rect
			(at -2.050034 -14.875002 270)
			(size 0.519938 1.4986)
			(layers "F.Cu" "F.Mask" "F.Paste")
			(net "M_B_CPU1_SA_CB<4>")
		)
		(pad "59" smd rect
			(at -2.050034 -14.025118 270)
			(size 0.519938 1.4986)
			(layers "F.Cu" "F.Mask" "F.Paste")
			(net "GND")
		)
		(pad "60" smd rect
			(at -2.050034 -13.17498 270)
			(size 0.519938 1.4986)
			(layers "F.Cu" "F.Mask" "F.Paste")
			(net "M_B_CPU1_SA_CB<5>")
		)
		(pad "61" smd rect
			(at -2.050034 -12.325096 270)
			(size 0.519938 1.4986)
			(layers "F.Cu" "F.Mask" "F.Paste")
			(net "GND")
		)
		(pad "62" smd rect
			(at -2.050034 -11.474958 270)
			(size 0.519938 1.4986)
			(layers "F.Cu" "F.Mask" "F.Paste")
			(net "M_B_CPU1_ALERT_N")
		)
		(pad "63" smd rect
			(at -2.050034 -10.625074 270)
			(size 0.519938 1.4986)
			(layers "F.Cu" "F.Mask" "F.Paste")
			(net "GND")
		)
		(pad "64" smd rect
			(at -2.050034 -9.774936 270)
			(size 0.519938 1.4986)
			(layers "F.Cu" "F.Mask" "F.Paste")
			(net "M_B_CPU1_SA_CS_N<0>")
		)
		(pad "65" smd rect
			(at -2.050034 -8.925052 270)
			(size 0.519938 1.4986)
			(layers "F.Cu" "F.Mask" "F.Paste")
			(net "GND")
		)
		(pad "66" smd rect
			(at -2.050034 -8.074914 270)
			(size 0.519938 1.4986)
			(layers "F.Cu" "F.Mask" "F.Paste")
			(net "M_B_CPU1_SA_CA<0>")
		)
		(pad "67" smd rect
			(at -2.050034 -7.22503 270)
			(size 0.519938 1.4986)
			(layers "F.Cu" "F.Mask" "F.Paste")
			(net "GND")
		)
		(pad "68" smd rect
			(at -2.050034 -6.374892 270)
			(size 0.519938 1.4986)
			(layers "F.Cu" "F.Mask" "F.Paste")
			(net "M_B_CPU1_SA_CA<2>")
		)
		(pad "69" smd rect
			(at -2.050034 -5.525008 270)
			(size 0.519938 1.4986)
			(layers "F.Cu" "F.Mask" "F.Paste")
			(net "GND")
		)
		(pad "70" smd rect
			(at -2.050034 -4.675124 270)
			(size 0.519938 1.4986)
			(layers "F.Cu" "F.Mask" "F.Paste")
			(net "M_B_CPU1_SA_CA<4>")
		)
		(pad "71" smd rect
			(at -2.050034 -3.824986 270)
			(size 0.519938 1.4986)
			(layers "F.Cu" "F.Mask" "F.Paste")
			(net "GND")
		)
		(pad "72" smd rect
			(at -2.050034 -2.975102 270)
			(size 0.519938 1.4986)
			(layers "F.Cu" "F.Mask" "F.Paste")
			(net "M_B_CPU1_SA_CA<6>")
		)
		(pad "73" smd rect
			(at -2.050034 -2.124964 270)
			(size 0.519938 1.4986)
			(layers "F.Cu" "F.Mask" "F.Paste")
			(net "GND")
		)
		(pad "74" smd rect
			(at -2.050034 -1.27508 270)
			(size 0.519938 1.4986)
			(layers "F.Cu" "F.Mask" "F.Paste")
			(net "M_B_CPU1_SA_PAR")
		)
		(pad "75" smd rect
			(at -2.050034 -0.424942 270)
			(size 0.519938 1.4986)
			(layers "F.Cu" "F.Mask" "F.Paste")
			(net "GND")
		)
		(pad "76" smd rect
			(at -2.050034 5.525008 270)
			(size 0.519938 1.4986)
			(layers "F.Cu" "F.Mask" "F.Paste")
			(net "M_B_CPU1_SB_CA<0>")
		)
		(pad "77" smd rect
			(at -2.050034 6.374892 270)
			(size 0.519938 1.4986)
			(layers "F.Cu" "F.Mask" "F.Paste")
			(net "GND")
		)
		(pad "78" smd rect
			(at -2.050034 7.22503 270)
			(size 0.519938 1.4986)
			(layers "F.Cu" "F.Mask" "F.Paste")
			(net "M_B_CPU1_SB_CA<2>")
		)
		(pad "79" smd rect
			(at -2.050034 8.074914 270)
			(size 0.519938 1.4986)
			(layers "F.Cu" "F.Mask" "F.Paste")
			(net "GND")
		)
		(pad "80" smd rect
			(at -2.050034 8.925052 270)
			(size 0.519938 1.4986)
			(layers "F.Cu" "F.Mask" "F.Paste")
			(net "M_B_CPU1_SB_CA<4>")
		)
		(pad "81" smd rect
			(at -2.050034 9.774936 270)
			(size 0.519938 1.4986)
			(layers "F.Cu" "F.Mask" "F.Paste")
			(net "GND")
		)
		(pad "82" smd rect
			(at -2.050034 10.625074 270)
			(size 0.519938 1.4986)
			(layers "F.Cu" "F.Mask" "F.Paste")
			(net "M_B_CPU1_SB_CA<6>")
		)
		(pad "83" smd rect
			(at -2.050034 11.474958 270)
			(size 0.519938 1.4986)
			(layers "F.Cu" "F.Mask" "F.Paste")
			(net "GND")
		)
		(pad "84" smd rect
			(at -2.050034 12.325096 270)
			(size 0.519938 1.4986)
			(layers "F.Cu" "F.Mask" "F.Paste")
			(net "M_B_CPU1_SB_CS_N<0>")
		)
		(pad "85" smd rect
			(at -2.050034 13.17498 270)
			(size 0.519938 1.4986)
			(layers "F.Cu" "F.Mask" "F.Paste")
			(net "GND")
		)
		(pad "86" smd rect
			(at -2.050034 14.025118 270)
			(size 0.519938 1.4986)
			(layers "F.Cu" "F.Mask" "F.Paste")
			(net "M_B_CPU1_SA_RSP<0>")
		)
		(pad "87" smd rect
			(at -2.050034 14.875002 270)
			(size 0.519938 1.4986)
			(layers "F.Cu" "F.Mask" "F.Paste")
			(net "M_B_CPU1_SB_RSP<0>")
		)
		(pad "88" smd rect
			(at -2.050034 15.724886 270)
			(size 0.519938 1.4986)
			(layers "F.Cu" "F.Mask" "F.Paste")
			(net "GND")
		)
		(pad "89" smd rect
			(at -2.050034 16.575024 270)
			(size 0.519938 1.4986)
			(layers "F.Cu" "F.Mask" "F.Paste")
			(net "M_B_CPU1_SB_CB<4>")
		)
		(pad "90" smd rect
			(at -2.050034 17.424908 270)
			(size 0.519938 1.4986)
			(layers "F.Cu" "F.Mask" "F.Paste")
			(net "GND")
		)
		(pad "91" smd rect
			(at -2.050034 18.275046 270)
			(size 0.519938 1.4986)
			(layers "F.Cu" "F.Mask" "F.Paste")
			(net "M_B_CPU1_SB_CB<5>")
		)
	)
)
